(kicad_pcb
	(version 20260206)
	(generator "pcbnew")
	(generator_version "10.0")
	(general
		(thickness 1.6)
		(legacy_teardrops no)
	)
	(paper "A4")
	(title_block
		(title "Bryce Canyon_F.DPB_16315-1-OCP.brd")
		(comment 1 "Bryce Canyon / footprints 1470-1477 of 2223")
	)
	(layers
		(0 "F.Cu" signal "TOP")
		(4 "In1.Cu" signal "L2GND")
		(6 "In2.Cu" signal "L3")
		(8 "In3.Cu" signal "L4GND")
		(10 "In4.Cu" signal "L5")
		(12 "In5.Cu" signal "L6VCC")
		(14 "In6.Cu" signal "L7VCC")
		(16 "In7.Cu" signal "L8")
		(18 "In8.Cu" signal "L9GND")
		(20 "In9.Cu" signal "L10")
		(22 "In10.Cu" signal "L11GND")
		(2 "B.Cu" signal "BOTTOM")
		(9 "F.Adhes" user "F.Adhesive")
		(11 "B.Adhes" user "B.Adhesive")
		(13 "F.Paste" user "Package Geometry/Pastemask Top")
		(15 "B.Paste" user "Package Geometry/Pastemask Bottom")
		(5 "F.SilkS" user "Ref Des/Silkscreen Top")
		(7 "B.SilkS" user "Ref Des/Silkscreen Bottom")
		(1 "F.Mask" user "Board Geometry/Soldermask Top")
		(3 "B.Mask" user "Board Geometry/Soldermask Bottom")
		(17 "Dwgs.User" user "User.Drawings")
		(19 "Cmts.User" user "User.Comments")
		(21 "Eco1.User" user "User.Eco1")
		(23 "Eco2.User" user "User.Eco2")
		(25 "Edge.Cuts" user "Board Geometry/Outline")
		(27 "Margin" user)
		(31 "F.CrtYd" user "Package Geometry/Place Bound Top")
		(29 "B.CrtYd" user "Package Geometry/Place Bound Bottom")
		(35 "F.Fab" user "Ref Des/Assembly Top")
		(33 "B.Fab" user "Ref Des/Assembly Bottom")
	)
	(footprint ""
		(layer "F.Cu")
		(at 458.3049 -45.252894 -90)
		(property "Reference" "Q205"
			(at 0 0 270)
			(layer "F.SilkS")
			(hide yes)
			(effects
				(font
					(size 1.27 1.27)
				)
			)
		)
		(property "Value" "2N7002KDW-GP"
			(at -2.3622 -8.2042 270)
			(unlocked yes)
			(layer "F.Fab")
			(hide yes)
			(effects
				(font
					(size 1.016 1.016)
					(thickness 0.1524)
				)
			)
		)
		(property "Device Type" "SOT-363H44"
			(at -2.3622 -10.1092 270)
			(unlocked yes)
			(layer "F.Fab")
			(hide yes)
			(effects
				(font
					(size 1.016 1.016)
					(thickness 0.1524)
				)
			)
		)
		(duplicate_pad_numbers_are_jumpers no)
		(fp_line
			(start -1.4478 1.7018)
			(end 1.4478 1.7018)
			(stroke
				(width 0.1524)
				(type default)
			)
			(layer "F.SilkS")
		)
		(fp_line
			(start 1.4478 1.7018)
			(end 1.4478 -1.7018)
			(stroke
				(width 0.1524)
				(type default)
			)
			(layer "F.SilkS")
		)
		(fp_line
			(start -1.27 1.524)
			(end -1.27 0.6604)
			(stroke
				(width 0.4826)
				(type default)
			)
			(layer "F.SilkS")
		)
		(fp_line
			(start -1.4478 -1.7018)
			(end -1.4478 1.7018)
			(stroke
				(width 0.1524)
				(type default)
			)
			(layer "F.SilkS")
		)
		(fp_line
			(start 1.4478 -1.7018)
			(end -1.4478 -1.7018)
			(stroke
				(width 0.1524)
				(type default)
			)
			(layer "F.SilkS")
		)
		(fp_poly
			(pts
				(xy -1.524 -1.778) (xy 1.524 -1.778) (xy 1.524 1.778) (xy -1.524 1.778)
			)
			(stroke
				(width 0)
				(type default)
			)
			(fill no)
			(layer "F.CrtYd")
		)
		(fp_poly
			(pts
				(xy -1.524 -1.778) (xy 1.524 -1.778) (xy 1.524 1.778) (xy -1.524 1.778)
			)
			(stroke
				(width 0)
				(type default)
			)
			(fill no)
			(layer "F.Fab")
		)
		(pad "1" smd rect
			(at -0.65024 0.9398 270)
			(size 0.4064 1.016)
			(layers "F.Cu" "F.Mask" "F.Paste")
			(net "GND")
		)
		(pad "2" smd rect
			(at 0 0.9398 270)
			(size 0.4064 1.016)
			(layers "F.Cu" "F.Mask" "F.Paste")
			(net "SW_PWR_R_HDD34")
		)
		(pad "3" smd rect
			(at 0.65024 0.9398 270)
			(size 0.4064 1.016)
			(layers "F.Cu" "F.Mask" "F.Paste")
			(net "SW_HDD_P34")
		)
		(pad "4" smd rect
			(at 0.65024 -0.9398 270)
			(size 0.4064 1.016)
			(layers "F.Cu" "F.Mask" "F.Paste")
			(net "GND")
		)
		(pad "5" smd rect
			(at 0 -0.9398 270)
			(size 0.4064 1.016)
			(layers "F.Cu" "F.Mask" "F.Paste")
			(net "SW_HDD_G34")
		)
		(pad "6" smd rect
			(at -0.65024 -0.9398 270)
			(size 0.4064 1.016)
			(layers "F.Cu" "F.Mask" "F.Paste")
			(net "SW_HDD_R34")
		)
	)
	(footprint ""
		(layer "F.Cu")
		(at 264.950448 10.238232)
		(property "Reference" "R134"
			(at 0 0 0)
			(layer "F.SilkS")
			(hide yes)
			(effects
				(font
					(size 1.27 1.27)
				)
			)
		)
		(property "Value" "4K7R2F-GP"
			(at 0.064008 -3.993896 0)
			(unlocked yes)
			(layer "F.Fab")
			(hide yes)
			(effects
				(font
					(size 1.016 1.016)
					(thickness 0.1524)
				)
			)
		)
		(property "Device Type" "R402H16"
			(at 0.064008 -5.517896 0)
			(unlocked yes)
			(layer "F.Fab")
			(hide yes)
			(effects
				(font
					(size 1.016 1.016)
					(thickness 0.1524)
				)
			)
		)
		(duplicate_pad_numbers_are_jumpers no)
		(fp_line
			(start -0.508 -0.9398)
			(end -0.508 0.9398)
			(stroke
				(width 0.1524)
				(type default)
			)
			(layer "F.SilkS")
		)
		(fp_line
			(start 0.508 -0.9398)
			(end -0.508 -0.9398)
			(stroke
				(width 0.1524)
				(type default)
			)
			(layer "F.SilkS")
		)
		(fp_rect
			(start -0.508 0.9398)
			(end 0.508 -0.9398)
			(stroke
				(width 0)
				(type default)
			)
			(fill no)
			(layer "F.CrtYd")
		)
		(fp_rect
			(start -0.508 0.9398)
			(end 0.508 -0.9398)
			(stroke
				(width 0)
				(type default)
			)
			(fill no)
			(layer "F.Fab")
		)
		(pad "1" smd custom
			(at 0 -0.4445)
			(size 0.1397 0.1397)
			(layers "F.Cu" "F.Mask" "F.Paste")
			(net "P5V_A_2")
			(options
				(clearance outline)
				(anchor circle)
			)
			(primitives
				(gr_poly
					(pts
						(arc
							(start -0.1778 -0.2794)
							(mid -0.249642 -0.249642)
							(end -0.2794 -0.1778)
						)
						(arc
							(start -0.2794 0.1778)
							(mid -0.249642 0.249642)
							(end -0.1778 0.2794)
						)
						(arc
							(start 0.1778 0.2794)
							(mid 0.249642 0.249642)
							(end 0.2794 0.1778)
						)
						(arc
							(start 0.2794 -0.1778)
							(mid 0.249642 -0.249642)
							(end 0.1778 -0.2794)
						)
					)
					(width 0)
					(fill yes)
				)
			)
		)
		(pad "2" smd custom
			(at 0 0.4445)
			(size 0.1397 0.1397)
			(layers "F.Cu" "F.Mask" "F.Paste")
			(net "USB_EN_1")
			(options
				(clearance outline)
				(anchor circle)
			)
			(primitives
				(gr_poly
					(pts
						(arc
							(start -0.1778 -0.2794)
							(mid -0.249642 -0.249642)
							(end -0.2794 -0.1778)
						)
						(arc
							(start -0.2794 0.1778)
							(mid -0.249642 0.249642)
							(end -0.1778 0.2794)
						)
						(arc
							(start 0.1778 0.2794)
							(mid 0.249642 0.249642)
							(end 0.2794 0.1778)
						)
						(arc
							(start 0.2794 -0.1778)
							(mid 0.249642 -0.249642)
							(end 0.1778 -0.2794)
						)
					)
					(width 0)
					(fill yes)
				)
			)
		)
	)
	(footprint ""
		(layer "F.Cu")
		(at 48.374046 -52.060094 90)
		(property "Reference" "R712"
			(at 0 0 90)
			(layer "F.SilkS")
			(hide yes)
			(effects
				(font
					(size 1.27 1.27)
				)
			)
		)
		(property "Value" "4K7R2J-2-GP"
			(at 0.064008 -3.993896 90)
			(unlocked yes)
			(layer "F.Fab")
			(hide yes)
			(effects
				(font
					(size 1.016 1.016)
					(thickness 0.1524)
				)
			)
		)
		(property "Device Type" "R402H16"
			(at 0.064008 -5.517896 90)
			(unlocked yes)
			(layer "F.Fab")
			(hide yes)
			(effects
				(font
					(size 1.016 1.016)
					(thickness 0.1524)
				)
			)
		)
		(duplicate_pad_numbers_are_jumpers no)
		(fp_line
			(start 0.508 -0.9398)
			(end -0.508 -0.9398)
			(stroke
				(width 0.1524)
				(type default)
			)
			(layer "F.SilkS")
		)
		(fp_line
			(start -0.508 -0.9398)
			(end -0.508 0.9398)
			(stroke
				(width 0.1524)
				(type default)
			)
			(layer "F.SilkS")
		)
		(fp_rect
			(start -0.508 0.9398)
			(end 0.508 -0.9398)
			(stroke
				(width 0)
				(type default)
			)
			(fill no)
			(layer "F.CrtYd")
		)
		(fp_rect
			(start -0.508 0.9398)
			(end 0.508 -0.9398)
			(stroke
				(width 0)
				(type default)
			)
			(fill no)
			(layer "F.Fab")
		)
		(pad "1" smd custom
			(at 0 -0.4445 90)
			(size 0.1397 0.1397)
			(layers "F.Cu" "F.Mask" "F.Paste")
			(net "P12V_A")
			(options
				(clearance outline)
				(anchor circle)
			)
			(primitives
				(gr_poly
					(pts
						(arc
							(start -0.1778 -0.2794)
							(mid -0.249642 -0.249642)
							(end -0.2794 -0.1778)
						)
						(arc
							(start -0.2794 0.1778)
							(mid -0.249642 0.249642)
							(end -0.1778 0.2794)
						)
						(arc
							(start 0.1778 0.2794)
							(mid 0.249642 0.249642)
							(end 0.2794 0.1778)
						)
						(arc
							(start 0.2794 -0.1778)
							(mid 0.249642 -0.249642)
							(end 0.1778 -0.2794)
						)
					)
					(width 0)
					(fill yes)
				)
			)
		)
		(pad "2" smd custom
			(at 0 0.4445 90)
			(size 0.1397 0.1397)
			(layers "F.Cu" "F.Mask" "F.Paste")
			(net "SW_HDD_P25")
			(options
				(clearance outline)
				(anchor circle)
			)
			(primitives
				(gr_poly
					(pts
						(arc
							(start -0.1778 -0.2794)
							(mid -0.249642 -0.249642)
							(end -0.2794 -0.1778)
						)
						(arc
							(start -0.2794 0.1778)
							(mid -0.249642 0.249642)
							(end -0.1778 0.2794)
						)
						(arc
							(start 0.1778 0.2794)
							(mid 0.249642 0.249642)
							(end 0.2794 0.1778)
						)
						(arc
							(start 0.2794 -0.1778)
							(mid 0.249642 -0.249642)
							(end 0.1778 -0.2794)
						)
					)
					(width 0)
					(fill yes)
				)
			)
		)
	)
	(footprint ""
		(layer "F.Cu")
		(at 161.997898 -177.169318 -90)
		(property "Reference" "R498"
			(at 0 0 270)
			(layer "F.SilkS")
			(hide yes)
			(effects
				(font
					(size 1.27 1.27)
				)
			)
		)
		(property "Value" "10KR2F-2-GP"
			(at 0.064008 -3.993896 270)
			(unlocked yes)
			(layer "F.Fab")
			(hide yes)
			(effects
				(font
					(size 1.016 1.016)
					(thickness 0.1524)
				)
			)
		)
		(property "Device Type" "R402H16"
			(at 0.064008 -5.517896 270)
			(unlocked yes)
			(layer "F.Fab")
			(hide yes)
			(effects
				(font
					(size 1.016 1.016)
					(thickness 0.1524)
				)
			)
		)
		(duplicate_pad_numbers_are_jumpers no)
		(fp_line
			(start -0.508 -0.9398)
			(end -0.508 0.9398)
			(stroke
				(width 0.1524)
				(type default)
			)
			(layer "F.SilkS")
		)
		(fp_line
			(start 0.508 -0.9398)
			(end -0.508 -0.9398)
			(stroke
				(width 0.1524)
				(type default)
			)
			(layer "F.SilkS")
		)
		(fp_rect
			(start -0.508 0.9398)
			(end 0.508 -0.9398)
			(stroke
				(width 0)
				(type default)
			)
			(fill no)
			(layer "F.CrtYd")
		)
		(fp_rect
			(start -0.508 0.9398)
			(end 0.508 -0.9398)
			(stroke
				(width 0)
				(type default)
			)
			(fill no)
			(layer "F.Fab")
		)
		(pad "1" smd custom
			(at 0 -0.4445 270)
			(size 0.1397 0.1397)
			(layers "F.Cu" "F.Mask" "F.Paste")
			(net "P3V3_STBY_A")
			(options
				(clearance outline)
				(anchor circle)
			)
			(primitives
				(gr_poly
					(pts
						(arc
							(start -0.1778 -0.2794)
							(mid -0.249642 -0.249642)
							(end -0.2794 -0.1778)
						)
						(arc
							(start -0.2794 0.1778)
							(mid -0.249642 0.249642)
							(end -0.1778 0.2794)
						)
						(arc
							(start 0.1778 0.2794)
							(mid 0.249642 0.249642)
							(end 0.2794 0.1778)
						)
						(arc
							(start 0.2794 -0.1778)
							(mid 0.249642 -0.249642)
							(end 0.1778 -0.2794)
						)
					)
					(width 0)
					(fill yes)
				)
			)
		)
		(pad "2" smd custom
			(at 0 0.4445 270)
			(size 0.1397 0.1397)
			(layers "F.Cu" "F.Mask" "F.Paste")
			(net "HDD_PRSNT_16")
			(options
				(clearance outline)
				(anchor circle)
			)
			(primitives
				(gr_poly
					(pts
						(arc
							(start -0.1778 -0.2794)
							(mid -0.249642 -0.249642)
							(end -0.2794 -0.1778)
						)
						(arc
							(start -0.2794 0.1778)
							(mid -0.249642 0.249642)
							(end -0.1778 0.2794)
						)
						(arc
							(start 0.1778 0.2794)
							(mid 0.249642 0.249642)
							(end 0.2794 0.1778)
						)
						(arc
							(start 0.2794 -0.1778)
							(mid 0.249642 -0.249642)
							(end 0.1778 -0.2794)
						)
					)
					(width 0)
					(fill yes)
				)
			)
		)
	)
	(footprint ""
		(layer "F.Cu")
		(at 231.668828 -389.763 90)
		(property "Reference" "C69"
			(at 0 0 90)
			(layer "F.SilkS")
			(hide yes)
			(effects
				(font
					(size 1.27 1.27)
				)
			)
		)
		(property "Value" "SC1U16V3KX-5GP"
			(at 0 -2.8194 90)
			(unlocked yes)
			(layer "F.Fab")
			(hide yes)
			(effects
				(font
					(size 1.016 1.016)
					(thickness 0.1524)
				)
			)
		)
		(property "Device Type" "C603H36"
			(at 0 -4.3434 90)
			(unlocked yes)
			(layer "F.Fab")
			(hide yes)
			(effects
				(font
					(size 1.016 1.016)
					(thickness 0.1524)
				)
			)
		)
		(duplicate_pad_numbers_are_jumpers no)
		(fp_line
			(start 0.508 0)
			(end -0.508 0)
			(stroke
				(width 0.2032)
				(type default)
			)
			(layer "F.SilkS")
		)
		(fp_rect
			(start -0.5842 1.3335)
			(end 0.5842 -1.3335)
			(stroke
				(width 0)
				(type default)
			)
			(fill no)
			(layer "F.CrtYd")
		)
		(fp_rect
			(start -0.5842 1.3335)
			(end 0.5842 -1.3335)
			(stroke
				(width 0)
				(type default)
			)
			(fill no)
			(layer "F.Fab")
		)
		(pad "1" smd custom
			(at 0 -0.762 90)
			(size 0.2159 0.2159)
			(layers "F.Cu" "F.Mask" "F.Paste")
			(net "P3V3_IN_BIAS")
			(options
				(clearance outline)
				(anchor circle)
			)
			(primitives
				(gr_poly
					(pts
						(arc
							(start -0.3302 -0.4318)
							(mid -0.402042 -0.402042)
							(end -0.4318 -0.3302)
						)
						(arc
							(start -0.4318 0.3302)
							(mid -0.402042 0.402042)
							(end -0.3302 0.4318)
						)
						(arc
							(start 0.3302 0.4318)
							(mid 0.402042 0.402042)
							(end 0.4318 0.3302)
						)
						(arc
							(start 0.4318 -0.3302)
							(mid 0.402042 -0.402042)
							(end 0.3302 -0.4318)
						)
					)
					(width 0)
					(fill yes)
				)
			)
		)
		(pad "2" smd custom
			(at 0 0.762 90)
			(size 0.2159 0.2159)
			(layers "F.Cu" "F.Mask" "F.Paste")
			(net "GND")
			(options
				(clearance outline)
				(anchor circle)
			)
			(primitives
				(gr_poly
					(pts
						(arc
							(start -0.3302 -0.4318)
							(mid -0.402042 -0.402042)
							(end -0.4318 -0.3302)
						)
						(arc
							(start -0.4318 0.3302)
							(mid -0.402042 0.402042)
							(end -0.3302 0.4318)
						)
						(arc
							(start 0.3302 0.4318)
							(mid 0.402042 0.402042)
							(end 0.4318 0.3302)
						)
						(arc
							(start 0.4318 -0.3302)
							(mid 0.402042 -0.402042)
							(end 0.3302 -0.4318)
						)
					)
					(width 0)
					(fill yes)
				)
			)
		)
	)
	(footprint ""
		(layer "F.Cu")
		(at 456.0189 -74.335894 180)
		(property "Reference" "C489"
			(at 0 0 180)
			(layer "F.SilkS")
			(hide yes)
			(effects
				(font
					(size 1.27 1.27)
				)
			)
		)
		(property "Value" "SC1U25V3KX-GP"
			(at 0 -2.8194 180)
			(unlocked yes)
			(layer "F.Fab")
			(hide yes)
			(effects
				(font
					(size 1.016 1.016)
					(thickness 0.1524)
				)
			)
		)
		(property "Device Type" "C603H36"
			(at 0 -4.3434 180)
			(unlocked yes)
			(layer "F.Fab")
			(hide yes)
			(effects
				(font
					(size 1.016 1.016)
					(thickness 0.1524)
				)
			)
		)
		(duplicate_pad_numbers_are_jumpers no)
		(fp_line
			(start 0.508 0)
			(end -0.508 0)
			(stroke
				(width 0.2032)
				(type default)
			)
			(layer "F.SilkS")
		)
		(fp_rect
			(start -0.5842 1.3335)
			(end 0.5842 -1.3335)
			(stroke
				(width 0)
				(type default)
			)
			(fill no)
			(layer "F.CrtYd")
		)
		(fp_rect
			(start -0.5842 1.3335)
			(end 0.5842 -1.3335)
			(stroke
				(width 0)
				(type default)
			)
			(fill no)
			(layer "F.Fab")
		)
		(pad "1" smd custom
			(at 0 -0.762 180)
			(size 0.2159 0.2159)
			(layers "F.Cu" "F.Mask" "F.Paste")
			(net "P12V_HDD34")
			(options
				(clearance outline)
				(anchor circle)
			)
			(primitives
				(gr_poly
					(pts
						(arc
							(start -0.3302 -0.4318)
							(mid -0.402042 -0.402042)
							(end -0.4318 -0.3302)
						)
						(arc
							(start -0.4318 0.3302)
							(mid -0.402042 0.402042)
							(end -0.3302 0.4318)
						)
						(arc
							(start 0.3302 0.4318)
							(mid 0.402042 0.402042)
							(end 0.4318 0.3302)
						)
						(arc
							(start 0.4318 -0.3302)
							(mid 0.402042 -0.402042)
							(end 0.3302 -0.4318)
						)
					)
					(width 0)
					(fill yes)
				)
			)
		)
		(pad "2" smd custom
			(at 0 0.762 180)
			(size 0.2159 0.2159)
			(layers "F.Cu" "F.Mask" "F.Paste")
			(net "GND")
			(options
				(clearance outline)
				(anchor circle)
			)
			(primitives
				(gr_poly
					(pts
						(arc
							(start -0.3302 -0.4318)
							(mid -0.402042 -0.402042)
							(end -0.4318 -0.3302)
						)
						(arc
							(start -0.4318 0.3302)
							(mid -0.402042 0.402042)
							(end -0.3302 0.4318)
						)
						(arc
							(start 0.3302 0.4318)
							(mid 0.402042 0.402042)
							(end 0.4318 0.3302)
						)
						(arc
							(start 0.4318 -0.3302)
							(mid 0.402042 -0.402042)
							(end 0.3302 -0.4318)
						)
					)
					(width 0)
					(fill yes)
				)
			)
		)
	)
	(footprint ""
		(layer "F.Cu")
		(at 149.196298 -163.554918 90)
		(property "Reference" "R511"
			(at 0 0 90)
			(layer "F.SilkS")
			(hide yes)
			(effects
				(font
					(size 1.27 1.27)
				)
			)
		)
		(property "Value" "4K7R2J-2-GP"
			(at 0.064008 -3.993896 90)
			(unlocked yes)
			(layer "F.Fab")
			(hide yes)
			(effects
				(font
					(size 1.016 1.016)
					(thickness 0.1524)
				)
			)
		)
		(property "Device Type" "R402H16"
			(at 0.064008 -5.517896 90)
			(unlocked yes)
			(layer "F.Fab")
			(hide yes)
			(effects
				(font
					(size 1.016 1.016)
					(thickness 0.1524)
				)
			)
		)
		(duplicate_pad_numbers_are_jumpers no)
		(fp_line
			(start 0.508 -0.9398)
			(end -0.508 -0.9398)
			(stroke
				(width 0.1524)
				(type default)
			)
			(layer "F.SilkS")
		)
		(fp_line
			(start -0.508 -0.9398)
			(end -0.508 0.9398)
			(stroke
				(width 0.1524)
				(type default)
			)
			(layer "F.SilkS")
		)
		(fp_rect
			(start -0.508 0.9398)
			(end 0.508 -0.9398)
			(stroke
				(width 0)
				(type default)
			)
			(fill no)
			(layer "F.CrtYd")
		)
		(fp_rect
			(start -0.508 0.9398)
			(end 0.508 -0.9398)
			(stroke
				(width 0)
				(type default)
			)
			(fill no)
			(layer "F.Fab")
		)
		(pad "1" smd custom
			(at 0 -0.4445 90)
			(size 0.1397 0.1397)
			(layers "F.Cu" "F.Mask" "F.Paste")
			(net "SW_PWR_R_HDD16")
			(options
				(clearance outline)
				(anchor circle)
			)
			(primitives
				(gr_poly
					(pts
						(arc
							(start -0.1778 -0.2794)
							(mid -0.249642 -0.249642)
							(end -0.2794 -0.1778)
						)
						(arc
							(start -0.2794 0.1778)
							(mid -0.249642 0.249642)
							(end -0.1778 0.2794)
						)
						(arc
							(start 0.1778 0.2794)
							(mid 0.249642 0.249642)
							(end 0.2794 0.1778)
						)
						(arc
							(start 0.2794 -0.1778)
							(mid 0.249642 -0.249642)
							(end 0.1778 -0.2794)
						)
					)
					(width 0)
					(fill yes)
				)
			)
		)
		(pad "2" smd custom
			(at 0 0.4445 90)
			(size 0.1397 0.1397)
			(layers "F.Cu" "F.Mask" "F.Paste")
			(net "GND")
			(options
				(clearance outline)
				(anchor circle)
			)
			(primitives
				(gr_poly
					(pts
						(arc
							(start -0.1778 -0.2794)
							(mid -0.249642 -0.249642)
							(end -0.2794 -0.1778)
						)
						(arc
							(start -0.2794 0.1778)
							(mid -0.249642 0.249642)
							(end -0.1778 0.2794)
						)
						(arc
							(start 0.1778 0.2794)
							(mid 0.249642 0.249642)
							(end 0.2794 0.1778)
						)
						(arc
							(start 0.2794 -0.1778)
							(mid 0.249642 -0.249642)
							(end 0.1778 -0.2794)
						)
					)
					(width 0)
					(fill yes)
				)
			)
		)
	)
	(footprint ""
		(layer "F.Cu")
		(at 350.1898 -68.6816)
		(property "Reference" "TP157"
			(at 0 0 0)
			(layer "F.SilkS")
			(hide yes)
			(effects
				(font
					(size 1.27 1.27)
				)
			)
		)
		(property "Value" "TPAD32-GP"
			(at -0.0508 -1.6764 0)
			(unlocked yes)
			(layer "F.Fab")
			(hide yes)
			(effects
				(font
					(size 1.016 1.016)
					(thickness 0.1524)
				)
			)
		)
		(property "Device Type" "TPAD32"
			(at -0.0508 -3.2004 0)
			(unlocked yes)
			(layer "F.Fab")
			(hide yes)
			(effects
				(font
					(size 1.016 1.016)
					(thickness 0.1524)
				)
			)
		)
		(duplicate_pad_numbers_are_jumpers no)
		(fp_poly
			(pts
				(arc
					(start 0.4064 0)
					(mid -0.4064 0)
					(end 0.4064 0)
				)
			)
			(stroke
				(width 0)
				(type default)
			)
			(fill no)
			(layer "F.CrtYd")
		)
		(fp_poly
			(pts
				(arc
					(start 0.7112 0)
					(mid -0.7112 0)
					(end 0.7112 0)
				)
			)
			(stroke
				(width 0)
				(type default)
			)
			(fill no)
			(layer "F.Fab")
		)
		(pad "1" smd circle
			(at 0 0)
			(size 0.8128 0.8128)
			(layers "F.Cu" "F.Mask" "F.Paste")
			(net "ACT_HDD_31")
		)
	)
)
